(kicad_pcb
	(version 20260206)
	(generator "pcbnew")
	(generator_version "10.0")
	(general
		(thickness 1.6)
		(legacy_teardrops no)
	)
	(paper "A4")
	(title_block
		(title "panther-plus-userver — 13130-1b_20150205.brd")
		(comment 1 "Honey Badger (Wiwynn) / footprint 1214 of 1509 (DIMM3), pads 72-78 of 210")
	)
	(layers
		(0 "F.Cu" signal "TOP")
		(4 "In1.Cu" signal "L2")
		(6 "In2.Cu" signal "L3")
		(8 "In3.Cu" signal "L4")
		(10 "In4.Cu" signal "L5")
		(12 "In5.Cu" signal "L6")
		(14 "In6.Cu" signal "L7")
		(16 "In7.Cu" signal "L8")
		(18 "In8.Cu" signal "L9")
		(20 "In9.Cu" signal "L10")
		(22 "In10.Cu" signal "L11")
		(2 "B.Cu" signal "BOTTOM")
		(9 "F.Adhes" user "F.Adhesive")
		(11 "B.Adhes" user "B.Adhesive")
		(13 "F.Paste" user "Package Geometry/Pastemask Top")
		(15 "B.Paste" user "Package Geometry/Pastemask Bottom")
		(5 "F.SilkS" user "Ref Des/Silkscreen Top")
		(7 "B.SilkS" user "Ref Des/Silkscreen Bottom")
		(1 "F.Mask" user "Board Geometry/Soldermask Top")
		(3 "B.Mask" user "Board Geometry/Soldermask Bottom")
		(17 "Dwgs.User" user "User.Drawings")
		(19 "Cmts.User" user "User.Comments")
		(21 "Eco1.User" user "User.Eco1")
		(23 "Eco2.User" user "User.Eco2")
		(25 "Edge.Cuts" user "Board Geometry/Outline")
		(27 "Margin" user)
		(31 "F.CrtYd" user "Package Geometry/Place Bound Top")
		(29 "B.CrtYd" user "Package Geometry/Place Bound Bottom")
		(35 "F.Fab" user "Ref Des/Assembly Top")
		(33 "B.Fab" user "Ref Des/Assembly Bottom")
	)
	(footprint ""
		(layer "B.Cu")
		(at 159.999934 -5.790692)
		(property "Reference" "DIMM3"
			(at 0 0 0)
			(layer "B.SilkS")
			(hide yes)
			(effects
				(font
					(size 1.27 1.27)
				)
				(justify mirror)
			)
		)
		(property "Value" "DDR3-204P-142-COLAY-1-GP-U"
			(at 41.312338 -16.676878 0)
			(unlocked yes)
			(layer "B.Fab")
			(hide yes)
			(effects
				(font
					(size 1.016 1.016)
					(thickness 0.1524)
				)
				(justify mirror)
			)
		)
		(property "Device Type" "AS0A626-J8R6-7H-COLAY-1"
			(at 41.312338 -18.200878 0)
			(unlocked yes)
			(layer "B.Fab")
			(hide yes)
			(effects
				(font
					(size 1.016 1.016)
					(thickness 0.1524)
				)
				(justify mirror)
			)
		)
		(duplicate_pad_numbers_are_jumpers no)
		(pad "70" smd custom
			(at -10.94994 4.100068 180)
			(size 0.1143 0.1143)
			(layers "B.Cu" "B.Mask" "B.Paste")
			(net "GND")
			(options
				(clearance outline)
				(anchor circle)
			)
			(primitives
				(gr_poly
					(pts
						(xy 0 -0.9017) (xy -0.03175 -0.89916) (xy -0.0635 -0.889) (xy -0.09144 -0.87376) (xy -0.11684 -0.85344)
						(xy -0.13716 -0.82804) (xy -0.1524 -0.8001) (xy -0.16256 -0.76835) (xy -0.1651 -0.7366) (xy -0.1651 0.13462)
						(xy -0.17272 0.14224) (xy -0.19812 0.1778) (xy -0.2032 0.18796) (xy -0.20701 0.19685) (xy -0.21209 0.20701)
						(xy -0.2159 0.21717) (xy -0.21844 0.22733) (xy -0.22225 0.23876) (xy -0.22352 0.24892) (xy -0.22606 0.25908)
						(xy -0.22733 0.27051) (xy -0.22733 0.28067) (xy -0.2286 0.2921) (xy -0.22733 0.30353) (xy -0.22733 0.31369)
						(xy -0.22606 0.32512) (xy -0.22352 0.33528) (xy -0.22225 0.34544) (xy -0.21844 0.35687) (xy -0.2159 0.36703)
						(xy -0.21209 0.37719) (xy -0.20701 0.38735) (xy -0.2032 0.39624) (xy -0.19812 0.4064) (xy -0.17272 0.44196)
						(xy -0.1651 0.44958) (xy -0.1651 0.7366) (xy -0.16256 0.76835) (xy -0.1524 0.8001) (xy -0.13716 0.82804)
						(xy -0.11684 0.85344) (xy -0.09144 0.87376) (xy -0.0635 0.889) (xy -0.03175 0.89916) (xy 0 0.9017)
						(xy 0.03175 0.89916) (xy 0.0635 0.889) (xy 0.09144 0.87376) (xy 0.11684 0.85344) (xy 0.13716 0.82804)
						(xy 0.1524 0.8001) (xy 0.16256 0.76835) (xy 0.1651 0.7366) (xy 0.1651 0.44958) (xy 0.17272 0.44196)
						(xy 0.19812 0.4064) (xy 0.2032 0.39624) (xy 0.20701 0.38735) (xy 0.21209 0.37719) (xy 0.2159 0.36703)
						(xy 0.21844 0.35687) (xy 0.22225 0.34544) (xy 0.22352 0.33528) (xy 0.22606 0.32512) (xy 0.22733 0.31369)
						(xy 0.22733 0.30353) (xy 0.2286 0.2921) (xy 0.22733 0.28067) (xy 0.22733 0.27051) (xy 0.22606 0.25908)
						(xy 0.22352 0.24892) (xy 0.22225 0.23876) (xy 0.21844 0.22733) (xy 0.2159 0.21717) (xy 0.21209 0.20701)
						(xy 0.20701 0.19685) (xy 0.2032 0.18796) (xy 0.19812 0.1778) (xy 0.17272 0.14224) (xy 0.1651 0.13462)
						(xy 0.1651 -0.7366) (xy 0.16256 -0.76835) (xy 0.1524 -0.8001) (xy 0.13716 -0.82804) (xy 0.11684 -0.85344)
						(xy 0.09144 -0.87376) (xy 0.0635 -0.889) (xy 0.03175 -0.89916)
					)
					(width 0)
					(fill yes)
				)
			)
		)
		(pad "71" smd custom
			(at -10.649966 -4.100068 180)
			(size 0.1143 0.1143)
			(layers "B.Cu" "B.Mask" "B.Paste")
			(net "M_B_ECC1")
			(options
				(clearance outline)
				(anchor circle)
			)
			(primitives
				(gr_poly
					(pts
						(xy 0 -0.9017) (xy -0.03175 -0.89916) (xy -0.0635 -0.889) (xy -0.09144 -0.87376) (xy -0.11684 -0.85344)
						(xy -0.13716 -0.82804) (xy -0.1524 -0.8001) (xy -0.16256 -0.76835) (xy -0.1651 -0.7366) (xy -0.1651 -0.19685)
						(xy -0.17272 -0.18923) (xy -0.17907 -0.18034) (xy -0.18669 -0.17145) (xy -0.19177 -0.16256) (xy -0.19812 -0.15367)
						(xy -0.20828 -0.13335) (xy -0.21971 -0.10287) (xy -0.22225 -0.09271) (xy -0.22479 -0.08128) (xy -0.22606 -0.07112)
						(xy -0.2286 -0.05969) (xy -0.2286 -0.01651) (xy -0.22606 -0.00508) (xy -0.22479 0.00508) (xy -0.22225 0.01651)
						(xy -0.21971 0.02667) (xy -0.20828 0.05715) (xy -0.19812 0.07747) (xy -0.19177 0.08636) (xy -0.18669 0.09525)
						(xy -0.17907 0.10414) (xy -0.17272 0.11303) (xy -0.1651 0.12065) (xy -0.1651 0.7366) (xy -0.16256 0.76835)
						(xy -0.1524 0.8001) (xy -0.13716 0.82804) (xy -0.11684 0.85344) (xy -0.09144 0.87376) (xy -0.0635 0.889)
						(xy -0.03175 0.89916) (xy 0 0.9017) (xy 0.03175 0.89916) (xy 0.0635 0.889) (xy 0.09144 0.87376)
						(xy 0.11684 0.85344) (xy 0.13716 0.82804) (xy 0.1524 0.8001) (xy 0.16256 0.76835) (xy 0.1651 0.7366)
						(xy 0.1651 0.11938) (xy 0.17272 0.11176) (xy 0.19812 0.0762) (xy 0.2032 0.06604) (xy 0.20701 0.05715)
						(xy 0.21209 0.04699) (xy 0.2159 0.03683) (xy 0.21844 0.02667) (xy 0.22225 0.01524) (xy 0.22352 0.00508)
						(xy 0.22606 -0.00508) (xy 0.22733 -0.01651) (xy 0.22733 -0.02667) (xy 0.2286 -0.0381) (xy 0.22733 -0.04953)
						(xy 0.22733 -0.05969) (xy 0.22606 -0.07112) (xy 0.22352 -0.08128) (xy 0.22225 -0.09144) (xy 0.21844 -0.10287)
						(xy 0.2159 -0.11303) (xy 0.21209 -0.12319) (xy 0.20701 -0.13335) (xy 0.2032 -0.14224) (xy 0.19812 -0.1524)
						(xy 0.17272 -0.18796) (xy 0.1651 -0.19558) (xy 0.1651 -0.7366) (xy 0.16256 -0.76835) (xy 0.1524 -0.8001)
						(xy 0.13716 -0.82804) (xy 0.11684 -0.85344) (xy 0.09144 -0.87376) (xy 0.0635 -0.889) (xy 0.03175 -0.89916)
					)
					(width 0)
					(fill yes)
				)
			)
		)
		(pad "72" smd custom
			(at -10.349992 4.100068 180)
			(size 0.1143 0.1143)
			(layers "B.Cu" "B.Mask" "B.Paste")
			(net "M_B_ECC4")
			(options
				(clearance outline)
				(anchor circle)
			)
			(primitives
				(gr_poly
					(pts
						(xy 0 -0.9017) (xy -0.03175 -0.89916) (xy -0.0635 -0.889) (xy -0.09144 -0.87376) (xy -0.11684 -0.85344)
						(xy -0.13716 -0.82804) (xy -0.1524 -0.8001) (xy -0.16256 -0.76835) (xy -0.1651 -0.7366) (xy -0.1651 -0.11938)
						(xy -0.17272 -0.11176) (xy -0.19812 -0.0762) (xy -0.2032 -0.06604) (xy -0.20701 -0.05715) (xy -0.21209 -0.04699)
						(xy -0.2159 -0.03683) (xy -0.21844 -0.02667) (xy -0.22225 -0.01524) (xy -0.22352 -0.00508) (xy -0.22606 0.00508)
						(xy -0.22733 0.01651) (xy -0.22733 0.02667) (xy -0.2286 0.0381) (xy -0.22733 0.04953) (xy -0.22733 0.05969)
						(xy -0.22606 0.07112) (xy -0.22352 0.08128) (xy -0.22225 0.09144) (xy -0.21844 0.10287) (xy -0.2159 0.11303)
						(xy -0.21209 0.12319) (xy -0.20701 0.13335) (xy -0.2032 0.14224) (xy -0.19812 0.1524) (xy -0.17272 0.18796)
						(xy -0.1651 0.19558) (xy -0.1651 0.7366) (xy -0.16256 0.76835) (xy -0.1524 0.8001) (xy -0.13716 0.82804)
						(xy -0.11684 0.85344) (xy -0.09144 0.87376) (xy -0.0635 0.889) (xy -0.03175 0.89916) (xy 0 0.9017)
						(xy 0.03175 0.89916) (xy 0.0635 0.889) (xy 0.09144 0.87376) (xy 0.11684 0.85344) (xy 0.13716 0.82804)
						(xy 0.1524 0.8001) (xy 0.16256 0.76835) (xy 0.1651 0.7366) (xy 0.1651 0.19685) (xy 0.17272 0.18923)
						(xy 0.17907 0.18034) (xy 0.18669 0.17145) (xy 0.19177 0.16256) (xy 0.19812 0.15367) (xy 0.20828 0.13335)
						(xy 0.21971 0.10287) (xy 0.22225 0.09271) (xy 0.22479 0.08128) (xy 0.22606 0.07112) (xy 0.2286 0.05969)
						(xy 0.2286 0.01651) (xy 0.22606 0.00508) (xy 0.22479 -0.00508) (xy 0.22225 -0.01651) (xy 0.21971 -0.02667)
						(xy 0.20828 -0.05715) (xy 0.19812 -0.07747) (xy 0.19177 -0.08636) (xy 0.18669 -0.09525) (xy 0.17907 -0.10414)
						(xy 0.17272 -0.11303) (xy 0.1651 -0.12065) (xy 0.1651 -0.7366) (xy 0.16256 -0.76835) (xy 0.1524 -0.8001)
						(xy 0.13716 -0.82804) (xy 0.11684 -0.85344) (xy 0.09144 -0.87376) (xy 0.0635 -0.889) (xy 0.03175 -0.89916)
					)
					(width 0)
					(fill yes)
				)
			)
		)
		(pad "73" smd custom
			(at -7.649972 -4.100068 180)
			(size 0.1143 0.1143)
			(layers "B.Cu" "B.Mask" "B.Paste")
			(net "GND")
			(options
				(clearance outline)
				(anchor circle)
			)
			(primitives
				(gr_poly
					(pts
						(xy 0 -0.9017) (xy -0.03175 -0.89916) (xy -0.0635 -0.889) (xy -0.09144 -0.87376) (xy -0.11684 -0.85344)
						(xy -0.13716 -0.82804) (xy -0.1524 -0.8001) (xy -0.16256 -0.76835) (xy -0.1651 -0.7366) (xy -0.1651 -0.44958)
						(xy -0.17272 -0.44196) (xy -0.19812 -0.4064) (xy -0.2032 -0.39624) (xy -0.20701 -0.38735) (xy -0.21209 -0.37719)
						(xy -0.2159 -0.36703) (xy -0.21844 -0.35687) (xy -0.22225 -0.34544) (xy -0.22352 -0.33528) (xy -0.22606 -0.32512)
						(xy -0.22733 -0.31369) (xy -0.22733 -0.30353) (xy -0.2286 -0.2921) (xy -0.22733 -0.28067) (xy -0.22733 -0.27051)
						(xy -0.22606 -0.25908) (xy -0.22352 -0.24892) (xy -0.22225 -0.23876) (xy -0.21844 -0.22733) (xy -0.2159 -0.21717)
						(xy -0.21209 -0.20701) (xy -0.20701 -0.19685) (xy -0.2032 -0.18796) (xy -0.19812 -0.1778) (xy -0.17272 -0.14224)
						(xy -0.1651 -0.13462) (xy -0.1651 0.7366) (xy -0.16256 0.76835) (xy -0.1524 0.8001) (xy -0.13716 0.82804)
						(xy -0.11684 0.85344) (xy -0.09144 0.87376) (xy -0.0635 0.889) (xy -0.03175 0.89916) (xy 0 0.9017)
						(xy 0.03175 0.89916) (xy 0.0635 0.889) (xy 0.09144 0.87376) (xy 0.11684 0.85344) (xy 0.13716 0.82804)
						(xy 0.1524 0.8001) (xy 0.16256 0.76835) (xy 0.1651 0.7366) (xy 0.1651 -0.13462) (xy 0.17272 -0.14224)
						(xy 0.19812 -0.1778) (xy 0.2032 -0.18796) (xy 0.20701 -0.19685) (xy 0.21209 -0.20701) (xy 0.2159 -0.21717)
						(xy 0.21844 -0.22733) (xy 0.22225 -0.23876) (xy 0.22352 -0.24892) (xy 0.22606 -0.25908) (xy 0.22733 -0.27051)
						(xy 0.22733 -0.28067) (xy 0.2286 -0.2921) (xy 0.22733 -0.30353) (xy 0.22733 -0.31369) (xy 0.22606 -0.32512)
						(xy 0.22352 -0.33528) (xy 0.22225 -0.34544) (xy 0.21844 -0.35687) (xy 0.2159 -0.36703) (xy 0.21209 -0.37719)
						(xy 0.20701 -0.38735) (xy 0.2032 -0.39624) (xy 0.19812 -0.4064) (xy 0.17272 -0.44196) (xy 0.1651 -0.44958)
						(xy 0.1651 -0.7366) (xy 0.16256 -0.76835) (xy 0.1524 -0.8001) (xy 0.13716 -0.82804) (xy 0.11684 -0.85344)
						(xy 0.09144 -0.87376) (xy 0.0635 -0.889) (xy 0.03175 -0.89916)
					)
					(width 0)
					(fill yes)
				)
			)
		)
		(pad "74" smd custom
			(at -7.349998 4.100068 180)
			(size 0.1143 0.1143)
			(layers "B.Cu" "B.Mask" "B.Paste")
			(net "M_B_ECC5")
			(options
				(clearance outline)
				(anchor circle)
			)
			(primitives
				(gr_poly
					(pts
						(xy 0 -0.9017) (xy -0.03175 -0.89916) (xy -0.0635 -0.889) (xy -0.09144 -0.87376) (xy -0.11684 -0.85344)
						(xy -0.13716 -0.82804) (xy -0.1524 -0.8001) (xy -0.16256 -0.76835) (xy -0.1651 -0.7366) (xy -0.1651 0.13462)
						(xy -0.17272 0.14224) (xy -0.19812 0.1778) (xy -0.2032 0.18796) (xy -0.20701 0.19685) (xy -0.21209 0.20701)
						(xy -0.2159 0.21717) (xy -0.21844 0.22733) (xy -0.22225 0.23876) (xy -0.22352 0.24892) (xy -0.22606 0.25908)
						(xy -0.22733 0.27051) (xy -0.22733 0.28067) (xy -0.2286 0.2921) (xy -0.22733 0.30353) (xy -0.22733 0.31369)
						(xy -0.22606 0.32512) (xy -0.22352 0.33528) (xy -0.22225 0.34544) (xy -0.21844 0.35687) (xy -0.2159 0.36703)
						(xy -0.21209 0.37719) (xy -0.20701 0.38735) (xy -0.2032 0.39624) (xy -0.19812 0.4064) (xy -0.17272 0.44196)
						(xy -0.1651 0.44958) (xy -0.1651 0.7366) (xy -0.16256 0.76835) (xy -0.1524 0.8001) (xy -0.13716 0.82804)
						(xy -0.11684 0.85344) (xy -0.09144 0.87376) (xy -0.0635 0.889) (xy -0.03175 0.89916) (xy 0 0.9017)
						(xy 0.03175 0.89916) (xy 0.0635 0.889) (xy 0.09144 0.87376) (xy 0.11684 0.85344) (xy 0.13716 0.82804)
						(xy 0.1524 0.8001) (xy 0.16256 0.76835) (xy 0.1651 0.7366) (xy 0.1651 0.44958) (xy 0.17272 0.44196)
						(xy 0.19812 0.4064) (xy 0.2032 0.39624) (xy 0.20701 0.38735) (xy 0.21209 0.37719) (xy 0.2159 0.36703)
						(xy 0.21844 0.35687) (xy 0.22225 0.34544) (xy 0.22352 0.33528) (xy 0.22606 0.32512) (xy 0.22733 0.31369)
						(xy 0.22733 0.30353) (xy 0.2286 0.2921) (xy 0.22733 0.28067) (xy 0.22733 0.27051) (xy 0.22606 0.25908)
						(xy 0.22352 0.24892) (xy 0.22225 0.23876) (xy 0.21844 0.22733) (xy 0.2159 0.21717) (xy 0.21209 0.20701)
						(xy 0.20701 0.19685) (xy 0.2032 0.18796) (xy 0.19812 0.1778) (xy 0.17272 0.14224) (xy 0.1651 0.13462)
						(xy 0.1651 -0.7366) (xy 0.16256 -0.76835) (xy 0.1524 -0.8001) (xy 0.13716 -0.82804) (xy 0.11684 -0.85344)
						(xy 0.09144 -0.87376) (xy 0.0635 -0.889) (xy 0.03175 -0.89916)
					)
					(width 0)
					(fill yes)
				)
			)
		)
		(pad "75" smd custom
			(at -7.050024 -4.100068 180)
			(size 0.1143 0.1143)
			(layers "B.Cu" "B.Mask" "B.Paste")
			(net "M_B_DQS_DN8")
			(options
				(clearance outline)
				(anchor circle)
			)
			(primitives
				(gr_poly
					(pts
						(xy 0 -0.9017) (xy -0.03175 -0.89916) (xy -0.0635 -0.889) (xy -0.09144 -0.87376) (xy -0.11684 -0.85344)
						(xy -0.13716 -0.82804) (xy -0.1524 -0.8001) (xy -0.16256 -0.76835) (xy -0.1651 -0.7366) (xy -0.1651 -0.19685)
						(xy -0.17272 -0.18923) (xy -0.17907 -0.18034) (xy -0.18669 -0.17145) (xy -0.19177 -0.16256) (xy -0.19812 -0.15367)
						(xy -0.20828 -0.13335) (xy -0.21971 -0.10287) (xy -0.22225 -0.09271) (xy -0.22479 -0.08128) (xy -0.22606 -0.07112)
						(xy -0.2286 -0.05969) (xy -0.2286 -0.01651) (xy -0.22606 -0.00508) (xy -0.22479 0.00508) (xy -0.22225 0.01651)
						(xy -0.21971 0.02667) (xy -0.20828 0.05715) (xy -0.19812 0.07747) (xy -0.19177 0.08636) (xy -0.18669 0.09525)
						(xy -0.17907 0.10414) (xy -0.17272 0.11303) (xy -0.1651 0.12065) (xy -0.1651 0.7366) (xy -0.16256 0.76835)
						(xy -0.1524 0.8001) (xy -0.13716 0.82804) (xy -0.11684 0.85344) (xy -0.09144 0.87376) (xy -0.0635 0.889)
						(xy -0.03175 0.89916) (xy 0 0.9017) (xy 0.03175 0.89916) (xy 0.0635 0.889) (xy 0.09144 0.87376)
						(xy 0.11684 0.85344) (xy 0.13716 0.82804) (xy 0.1524 0.8001) (xy 0.16256 0.76835) (xy 0.1651 0.7366)
						(xy 0.1651 0.11938) (xy 0.17272 0.11176) (xy 0.19812 0.0762) (xy 0.2032 0.06604) (xy 0.20701 0.05715)
						(xy 0.21209 0.04699) (xy 0.2159 0.03683) (xy 0.21844 0.02667) (xy 0.22225 0.01524) (xy 0.22352 0.00508)
						(xy 0.22606 -0.00508) (xy 0.22733 -0.01651) (xy 0.22733 -0.02667) (xy 0.2286 -0.0381) (xy 0.22733 -0.04953)
						(xy 0.22733 -0.05969) (xy 0.22606 -0.07112) (xy 0.22352 -0.08128) (xy 0.22225 -0.09144) (xy 0.21844 -0.10287)
						(xy 0.2159 -0.11303) (xy 0.21209 -0.12319) (xy 0.20701 -0.13335) (xy 0.2032 -0.14224) (xy 0.19812 -0.1524)
						(xy 0.17272 -0.18796) (xy 0.1651 -0.19558) (xy 0.1651 -0.7366) (xy 0.16256 -0.76835) (xy 0.1524 -0.8001)
						(xy 0.13716 -0.82804) (xy 0.11684 -0.85344) (xy 0.09144 -0.87376) (xy 0.0635 -0.889) (xy 0.03175 -0.89916)
					)
					(width 0)
					(fill yes)
				)
			)
		)
		(pad "76" smd custom
			(at -6.75005 4.100068 180)
			(size 0.1143 0.1143)
			(layers "B.Cu" "B.Mask" "B.Paste")
			(net "GND")
			(options
				(clearance outline)
				(anchor circle)
			)
			(primitives
				(gr_poly
					(pts
						(xy 0 -0.9017) (xy -0.03175 -0.89916) (xy -0.0635 -0.889) (xy -0.09144 -0.87376) (xy -0.11684 -0.85344)
						(xy -0.13716 -0.82804) (xy -0.1524 -0.8001) (xy -0.16256 -0.76835) (xy -0.1651 -0.7366) (xy -0.1651 -0.11938)
						(xy -0.17272 -0.11176) (xy -0.19812 -0.0762) (xy -0.2032 -0.06604) (xy -0.20701 -0.05715) (xy -0.21209 -0.04699)
						(xy -0.2159 -0.03683) (xy -0.21844 -0.02667) (xy -0.22225 -0.01524) (xy -0.22352 -0.00508) (xy -0.22606 0.00508)
						(xy -0.22733 0.01651) (xy -0.22733 0.02667) (xy -0.2286 0.0381) (xy -0.22733 0.04953) (xy -0.22733 0.05969)
						(xy -0.22606 0.07112) (xy -0.22352 0.08128) (xy -0.22225 0.09144) (xy -0.21844 0.10287) (xy -0.2159 0.11303)
						(xy -0.21209 0.12319) (xy -0.20701 0.13335) (xy -0.2032 0.14224) (xy -0.19812 0.1524) (xy -0.17272 0.18796)
						(xy -0.1651 0.19558) (xy -0.1651 0.7366) (xy -0.16256 0.76835) (xy -0.1524 0.8001) (xy -0.13716 0.82804)
						(xy -0.11684 0.85344) (xy -0.09144 0.87376) (xy -0.0635 0.889) (xy -0.03175 0.89916) (xy 0 0.9017)
						(xy 0.03175 0.89916) (xy 0.0635 0.889) (xy 0.09144 0.87376) (xy 0.11684 0.85344) (xy 0.13716 0.82804)
						(xy 0.1524 0.8001) (xy 0.16256 0.76835) (xy 0.1651 0.7366) (xy 0.1651 0.19685) (xy 0.17272 0.18923)
						(xy 0.17907 0.18034) (xy 0.18669 0.17145) (xy 0.19177 0.16256) (xy 0.19812 0.15367) (xy 0.20828 0.13335)
						(xy 0.21971 0.10287) (xy 0.22225 0.09271) (xy 0.22479 0.08128) (xy 0.22606 0.07112) (xy 0.2286 0.05969)
						(xy 0.2286 0.01651) (xy 0.22606 0.00508) (xy 0.22479 -0.00508) (xy 0.22225 -0.01651) (xy 0.21971 -0.02667)
						(xy 0.20828 -0.05715) (xy 0.19812 -0.07747) (xy 0.19177 -0.08636) (xy 0.18669 -0.09525) (xy 0.17907 -0.10414)
						(xy 0.17272 -0.11303) (xy 0.1651 -0.12065) (xy 0.1651 -0.7366) (xy 0.16256 -0.76835) (xy 0.1524 -0.8001)
						(xy 0.13716 -0.82804) (xy 0.11684 -0.85344) (xy 0.09144 -0.87376) (xy 0.0635 -0.889) (xy 0.03175 -0.89916)
					)
					(width 0)
					(fill yes)
				)
			)
		)
	)
)
